(kicad_pcb
	(version 20260206)
	(generator "pcbnew")
	(generator_version "10.0")
	(general
		(thickness 1.6)
		(legacy_teardrops no)
	)
	(paper "A4")
	(title_block
		(title "Bryce Canyon_IOM_M2_16342-2_OCP.brd")
		(comment 1 "Bryce Canyon / footprints 519-520 of 1146")
	)
	(layers
		(0 "F.Cu" signal "TOP")
		(4 "In1.Cu" signal "L2GND")
		(6 "In2.Cu" signal "L3")
		(8 "In3.Cu" signal "L4VCC")
		(10 "In4.Cu" signal "L5VCC")
		(12 "In5.Cu" signal "L6")
		(14 "In6.Cu" signal "L7GND")
		(2 "B.Cu" signal "BOTTOM")
		(9 "F.Adhes" user "F.Adhesive")
		(11 "B.Adhes" user "B.Adhesive")
		(13 "F.Paste" user "Package Geometry/Pastemask Top")
		(15 "B.Paste" user "Package Geometry/Pastemask Bottom")
		(5 "F.SilkS" user "Ref Des/Silkscreen Top")
		(7 "B.SilkS" user "Ref Des/Silkscreen Bottom")
		(1 "F.Mask" user "Board Geometry/Soldermask Top")
		(3 "B.Mask" user "Board Geometry/Soldermask Bottom")
		(17 "Dwgs.User" user "User.Drawings")
		(19 "Cmts.User" user "User.Comments")
		(21 "Eco1.User" user "User.Eco1")
		(23 "Eco2.User" user "User.Eco2")
		(25 "Edge.Cuts" user "Board Geometry/Outline")
		(27 "Margin" user)
		(31 "F.CrtYd" user "Package Geometry/Place Bound Top")
		(29 "B.CrtYd" user "Package Geometry/Place Bound Bottom")
		(35 "F.Fab" user "Ref Des/Assembly Top")
		(33 "B.Fab" user "Ref Des/Assembly Bottom")
	)
	(footprint ""
		(layer "F.Cu")
		(at 179.399946 -129.599944)
		(property "Reference" "M2"
			(at 0 0 0)
			(layer "F.SilkS")
			(hide yes)
			(effects
				(font
					(size 1.27 1.27)
				)
			)
		)
		(property "Value" "SKT-MINI75P-11-GP"
			(at 12.6619 2.2733 0)
			(unlocked yes)
			(layer "F.Fab")
			(hide yes)
			(effects
				(font
					(size 1.016 1.016)
					(thickness 0.1524)
				)
			)
		)
		(property "Device Type" "MDT580M01001"
			(at 12.6619 0.7493 0)
			(unlocked yes)
			(layer "F.Fab")
			(hide yes)
			(effects
				(font
					(size 1.016 1.016)
					(thickness 0.1524)
				)
			)
		)
		(duplicate_pad_numbers_are_jumpers no)
		(fp_line
			(start -11.2522 -6.2992)
			(end 11.2522 -6.2992)
			(stroke
				(width 0.1524)
				(type default)
			)
			(layer "F.SilkS")
		)
		(fp_line
			(start -11.2522 3.302)
			(end -11.2522 -6.2992)
			(stroke
				(width 0.1524)
				(type default)
			)
			(layer "F.SilkS")
		)
		(fp_line
			(start -9.525 -6.3881)
			(end -9.017 -6.3881)
			(stroke
				(width 0.3302)
				(type default)
			)
			(layer "F.SilkS")
		)
		(fp_line
			(start 11.2522 -6.2992)
			(end 11.2522 3.302)
			(stroke
				(width 0.1524)
				(type default)
			)
			(layer "F.SilkS")
		)
		(fp_line
			(start 11.2522 3.302)
			(end -11.2522 3.302)
			(stroke
				(width 0.1524)
				(type default)
			)
			(layer "F.SilkS")
		)
		(fp_poly
			(pts
				(xy -9.273794 -6.315202) (xy -8.841994 -6.747002) (xy -9.705594 -6.747002)
			)
			(stroke
				(width 0)
				(type default)
			)
			(fill yes)
			(layer "F.SilkS")
		)
		(fp_rect
			(start -10.9982 2.8448)
			(end 10.9982 -5.6896)
			(stroke
				(width 0)
				(type default)
			)
			(fill no)
			(layer "F.CrtYd")
		)
		(fp_poly
			(pts
				(xy -11.5062 3.556) (xy -11.5062 -6.5532) (xy 11.5062 -6.5532) (xy 11.5062 -0.00635) (xy 10.9982 -0.00635)
				(xy 10.9982 -5.6896) (xy -10.9982 -5.6896) (xy -10.9982 2.8448) (xy 10.9982 2.8448) (xy 10.9982 0.00635)
				(xy 11.5062 0.00635) (xy 11.5062 3.556)
			)
			(stroke
				(width 0)
				(type default)
			)
			(fill no)
			(layer "F.CrtYd")
		)
		(fp_rect
			(start -11.5062 3.556)
			(end 11.5062 -6.5532)
			(stroke
				(width 0)
				(type default)
			)
			(fill no)
			(layer "F.Fab")
		)
		(pad "" np_thru_hole circle
			(at -9.99998 0)
			(size 0.254 0.254)
			(drill 1.1176)
			(layers "*.Cu" "*.Mask")
			(clearance 0.7874)
			(thermal_gap 0.7874)
		)
		(pad "" np_thru_hole circle
			(at 9.99998 0)
			(size 0.254 0.254)
			(drill 1.6002)
			(layers "*.Cu" "*.Mask")
			(clearance 1.0287)
			(thermal_gap 1.0287)
		)
		(pad "1" smd rect
			(at -9.249918 -5.275072)
			(size 0.3048 1.5494)
			(layers "F.Cu" "F.Mask" "F.Paste")
			(net "M2_2_PRESENT_N_R")
		)
		(pad "2" smd rect
			(at -8.999982 2.275078)
			(size 0.3048 1.5494)
			(layers "F.Cu" "F.Mask" "F.Paste")
			(net "P3V3_M2")
		)
		(pad "3" smd rect
			(at -8.750046 -5.275072)
			(size 0.3048 1.5494)
			(layers "F.Cu" "F.Mask" "F.Paste")
			(net "GND")
		)
		(pad "4" smd rect
			(at -8.50011 2.275078)
			(size 0.3048 1.5494)
			(layers "F.Cu" "F.Mask" "F.Paste")
			(net "P3V3_M2")
		)
		(pad "5" smd rect
			(at -8.24992 -5.275072)
			(size 0.3048 1.5494)
			(layers "F.Cu" "F.Mask" "F.Paste")
			(net "PCIE_IOM_TO_COMP_15_DN")
		)
		(pad "6" smd rect
			(at -7.999984 2.275078)
			(size 0.3048 1.5494)
			(layers "F.Cu" "F.Mask" "F.Paste")
			(net "Net_603")
		)
		(pad "7" smd rect
			(at -7.750048 -5.275072)
			(size 0.3048 1.5494)
			(layers "F.Cu" "F.Mask" "F.Paste")
			(net "PCIE_IOM_TO_COMP_15_DP")
		)
		(pad "8" smd rect
			(at -7.500112 2.275078)
			(size 0.3048 1.5494)
			(layers "F.Cu" "F.Mask" "F.Paste")
			(net "Net_604")
		)
		(pad "9" smd rect
			(at -7.249922 -5.275072)
			(size 0.3048 1.5494)
			(layers "F.Cu" "F.Mask" "F.Paste")
			(net "GND")
		)
		(pad "10" smd rect
			(at -6.999986 2.275078)
			(size 0.3048 1.5494)
			(layers "F.Cu" "F.Mask" "F.Paste")
			(net "M2_2_ACTIVE_N")
		)
		(pad "11" smd rect
			(at -6.75005 -5.275072)
			(size 0.3048 1.5494)
			(layers "F.Cu" "F.Mask" "F.Paste")
			(net "PCIE_COMP_TO_IOM_15_DN")
		)
		(pad "12" smd rect
			(at -6.500114 2.275078)
			(size 0.3048 1.5494)
			(layers "F.Cu" "F.Mask" "F.Paste")
			(net "P3V3_M2")
		)
		(pad "13" smd rect
			(at -6.249924 -5.275072)
			(size 0.3048 1.5494)
			(layers "F.Cu" "F.Mask" "F.Paste")
			(net "PCIE_COMP_TO_IOM_15_DP")
		)
		(pad "14" smd rect
			(at -5.999988 2.275078)
			(size 0.3048 1.5494)
			(layers "F.Cu" "F.Mask" "F.Paste")
			(net "P3V3_M2")
		)
		(pad "15" smd rect
			(at -5.750052 -5.275072)
			(size 0.3048 1.5494)
			(layers "F.Cu" "F.Mask" "F.Paste")
			(net "GND")
		)
		(pad "16" smd rect
			(at -5.500116 2.275078)
			(size 0.3048 1.5494)
			(layers "F.Cu" "F.Mask" "F.Paste")
			(net "P3V3_M2")
		)
		(pad "17" smd rect
			(at -5.249926 -5.275072)
			(size 0.3048 1.5494)
			(layers "F.Cu" "F.Mask" "F.Paste")
			(net "PCIE_IOM_TO_COMP_14_DN")
		)
		(pad "18" smd rect
			(at -4.99999 2.275078)
			(size 0.3048 1.5494)
			(layers "F.Cu" "F.Mask" "F.Paste")
			(net "P3V3_M2")
		)
		(pad "19" smd rect
			(at -4.750054 -5.275072)
			(size 0.3048 1.5494)
			(layers "F.Cu" "F.Mask" "F.Paste")
			(net "PCIE_IOM_TO_COMP_14_DP")
		)
		(pad "20" smd rect
			(at -4.500118 2.275078)
			(size 0.3048 1.5494)
			(layers "F.Cu" "F.Mask" "F.Paste")
			(net "Net_605")
		)
		(pad "21" smd rect
			(at -4.249928 -5.275072)
			(size 0.3048 1.5494)
			(layers "F.Cu" "F.Mask" "F.Paste")
			(net "GND")
		)
		(pad "22" smd rect
			(at -3.999992 2.275078)
			(size 0.3048 1.5494)
			(layers "F.Cu" "F.Mask" "F.Paste")
			(net "Net_606")
		)
		(pad "23" smd rect
			(at -3.750056 -5.275072)
			(size 0.3048 1.5494)
			(layers "F.Cu" "F.Mask" "F.Paste")
			(net "PCIE_COMP_TO_IOM_14_DN")
		)
		(pad "24" smd rect
			(at -3.50012 2.275078)
			(size 0.3048 1.5494)
			(layers "F.Cu" "F.Mask" "F.Paste")
			(net "Net_593")
		)
		(pad "25" smd rect
			(at -3.24993 -5.275072)
			(size 0.3048 1.5494)
			(layers "F.Cu" "F.Mask" "F.Paste")
			(net "PCIE_COMP_TO_IOM_14_DP")
		)
		(pad "26" smd rect
			(at -2.999994 2.275078)
			(size 0.3048 1.5494)
			(layers "F.Cu" "F.Mask" "F.Paste")
			(net "Net_594")
		)
		(pad "27" smd rect
			(at -2.750058 -5.275072)
			(size 0.3048 1.5494)
			(layers "F.Cu" "F.Mask" "F.Paste")
			(net "GND")
		)
		(pad "28" smd rect
			(at -2.500122 2.275078)
			(size 0.3048 1.5494)
			(layers "F.Cu" "F.Mask" "F.Paste")
			(net "Net_595")
		)
		(pad "29" smd rect
			(at -2.249932 -5.275072)
			(size 0.3048 1.5494)
			(layers "F.Cu" "F.Mask" "F.Paste")
			(net "PCIE_IOM_TO_COMP_13_DN")
		)
		(pad "30" smd rect
			(at -1.999996 2.275078)
			(size 0.3048 1.5494)
			(layers "F.Cu" "F.Mask" "F.Paste")
			(net "Net_596")
		)
		(pad "31" smd rect
			(at -1.75006 -5.275072)
			(size 0.3048 1.5494)
			(layers "F.Cu" "F.Mask" "F.Paste")
			(net "PCIE_IOM_TO_COMP_13_DP")
		)
		(pad "32" smd rect
			(at -1.500124 2.275078)
			(size 0.3048 1.5494)
			(layers "F.Cu" "F.Mask" "F.Paste")
			(net "Net_597")
		)
		(pad "33" smd rect
			(at -1.249934 -5.275072)
			(size 0.3048 1.5494)
			(layers "F.Cu" "F.Mask" "F.Paste")
			(net "GND")
		)
		(pad "34" smd rect
			(at -0.999998 2.275078)
			(size 0.3048 1.5494)
			(layers "F.Cu" "F.Mask" "F.Paste")
			(net "Net_598")
		)
		(pad "35" smd rect
			(at -0.750062 -5.275072)
			(size 0.3048 1.5494)
			(layers "F.Cu" "F.Mask" "F.Paste")
			(net "PCIE_COMP_TO_IOM_13_DN")
		)
		(pad "36" smd rect
			(at -0.500126 2.275078)
			(size 0.3048 1.5494)
			(layers "F.Cu" "F.Mask" "F.Paste")
			(net "Net_599")
		)
		(pad "37" smd rect
			(at -0.249936 -5.275072)
			(size 0.3048 1.5494)
			(layers "F.Cu" "F.Mask" "F.Paste")
			(net "PCIE_COMP_TO_IOM_13_DP")
		)
		(pad "38" smd rect
			(at 0 2.275078)
			(size 0.3048 1.5494)
			(layers "F.Cu" "F.Mask" "F.Paste")
			(net "Net_600")
		)
		(pad "39" smd rect
			(at 0.249936 -5.275072)
			(size 0.3048 1.5494)
			(layers "F.Cu" "F.Mask" "F.Paste")
			(net "GND")
		)
		(pad "40" smd rect
			(at 0.500126 2.275078)
			(size 0.3048 1.5494)
			(layers "F.Cu" "F.Mask" "F.Paste")
			(net "I2C_M2_2_1V8_SCL")
		)
		(pad "41" smd rect
			(at 0.750062 -5.275072)
			(size 0.3048 1.5494)
			(layers "F.Cu" "F.Mask" "F.Paste")
			(net "PCIE_IOM_TO_COMP_12_DN")
		)
		(pad "42" smd rect
			(at 0.999998 2.275078)
			(size 0.3048 1.5494)
			(layers "F.Cu" "F.Mask" "F.Paste")
			(net "I2C_M2_2_1V8_SDA")
		)
		(pad "43" smd rect
			(at 1.249934 -5.275072)
			(size 0.3048 1.5494)
			(layers "F.Cu" "F.Mask" "F.Paste")
			(net "PCIE_IOM_TO_COMP_12_DP")
		)
		(pad "44" smd rect
			(at 1.500124 2.275078)
			(size 0.3048 1.5494)
			(layers "F.Cu" "F.Mask" "F.Paste")
			(net "M2_2_ALERT#")
		)
		(pad "45" smd rect
			(at 1.75006 -5.275072)
			(size 0.3048 1.5494)
			(layers "F.Cu" "F.Mask" "F.Paste")
			(net "GND")
		)
		(pad "46" smd rect
			(at 1.999996 2.275078)
			(size 0.3048 1.5494)
			(layers "F.Cu" "F.Mask" "F.Paste")
			(net "Net_601")
		)
		(pad "47" smd rect
			(at 2.249932 -5.275072)
			(size 0.3048 1.5494)
			(layers "F.Cu" "F.Mask" "F.Paste")
			(net "PCIE_COMP_TO_IOM_12_DN")
		)
		(pad "48" smd rect
			(at 2.500122 2.275078)
			(size 0.3048 1.5494)
			(layers "F.Cu" "F.Mask" "F.Paste")
			(net "Net_602")
		)
		(pad "49" smd rect
			(at 2.750058 -5.275072)
			(size 0.3048 1.5494)
			(layers "F.Cu" "F.Mask" "F.Paste")
			(net "PCIE_COMP_TO_IOM_12_DP")
		)
		(pad "50" smd rect
			(at 2.999994 2.275078)
			(size 0.3048 1.5494)
			(layers "F.Cu" "F.Mask" "F.Paste")
			(net "PCIE_COMP_TO_IOM_RST_3")
		)
		(pad "51" smd rect
			(at 3.24993 -5.275072)
			(size 0.3048 1.5494)
			(layers "F.Cu" "F.Mask" "F.Paste")
			(net "GND")
		)
		(pad "52" smd rect
			(at 3.50012 2.275078)
			(size 0.3048 1.5494)
			(layers "F.Cu" "F.Mask" "F.Paste")
			(net "M2_2_CLKREQ#")
		)
		(pad "53" smd rect
			(at 3.750056 -5.275072)
			(size 0.3048 1.5494)
			(layers "F.Cu" "F.Mask" "F.Paste")
			(net "PCIE_COMP_TO_IOM_CLK_3_DN")
		)
		(pad "54" smd rect
			(at 3.999992 2.275078)
			(size 0.3048 1.5494)
			(layers "F.Cu" "F.Mask" "F.Paste")
			(net "Net_590")
		)
		(pad "55" smd rect
			(at 4.249928 -5.275072)
			(size 0.3048 1.5494)
			(layers "F.Cu" "F.Mask" "F.Paste")
			(net "PCIE_COMP_TO_IOM_CLK_3_DP")
		)
		(pad "56" smd rect
			(at 4.500118 2.275078)
			(size 0.3048 1.5494)
			(layers "F.Cu" "F.Mask" "F.Paste")
			(net "TP_M2_2_MFG_DAT")
		)
		(pad "57" smd rect
			(at 4.750054 -5.275072)
			(size 0.3048 1.5494)
			(layers "F.Cu" "F.Mask" "F.Paste")
			(net "GND")
		)
		(pad "58" smd rect
			(at 4.99999 2.275078)
			(size 0.3048 1.5494)
			(layers "F.Cu" "F.Mask" "F.Paste")
			(net "TP_M2_2_MFG_CLK")
		)
		(pad "67" smd rect
			(at 7.249922 -5.275072)
			(size 0.3048 1.5494)
			(layers "F.Cu" "F.Mask" "F.Paste")
			(net "Net_588")
		)
		(pad "68" smd rect
			(at 7.500112 2.275078)
			(size 0.3048 1.5494)
			(layers "F.Cu" "F.Mask" "F.Paste")
			(net "Net_591")
		)
		(pad "69" smd rect
			(at 7.750048 -5.275072)
			(size 0.3048 1.5494)
			(layers "F.Cu" "F.Mask" "F.Paste")
			(net "Net_589")
		)
		(pad "70" smd rect
			(at 7.999984 2.275078)
			(size 0.3048 1.5494)
			(layers "F.Cu" "F.Mask" "F.Paste")
			(net "P3V3_M2")
		)
		(pad "71" smd rect
			(at 8.24992 -5.275072)
			(size 0.3048 1.5494)
			(layers "F.Cu" "F.Mask" "F.Paste")
			(net "GND")
		)
		(pad "72" smd rect
			(at 8.50011 2.275078)
			(size 0.3048 1.5494)
			(layers "F.Cu" "F.Mask" "F.Paste")
			(net "P3V3_M2")
		)
		(pad "73" smd rect
			(at 8.750046 -5.275072)
			(size 0.3048 1.5494)
			(layers "F.Cu" "F.Mask" "F.Paste")
			(net "GND")
		)
		(pad "74" smd rect
			(at 8.999982 2.275078)
			(size 0.3048 1.5494)
			(layers "F.Cu" "F.Mask" "F.Paste")
			(net "P3V3_M2")
		)
		(pad "75" smd rect
			(at 9.249918 -5.275072)
			(size 0.3048 1.5494)
			(layers "F.Cu" "F.Mask" "F.Paste")
			(net "GND")
		)
		(pad "76" smd rect
			(at -10.349992 -4.500118)
			(size 1.1938 2.7432)
			(layers "F.Cu" "F.Mask" "F.Paste")
			(net "GND")
		)
		(pad "77" smd rect
			(at 10.349992 -4.500118)
			(size 1.1938 2.7432)
			(layers "F.Cu" "F.Mask" "F.Paste")
			(net "GND")
		)
		(zone
			(layer "F.Cu")
			(hatch none 0.5)
			(connect_pads
				(clearance 0)
			)
			(min_thickness 0.25)
			(keepout
				(tracks allowed)
				(vias not_allowed)
				(pads allowed)
				(copperpour not_allowed)
				(footprints allowed)
			)
			(placement
				(enabled no)
				(sheetname "")
			)
			(fill
				(thermal_gap 0.5)
				(thermal_bridge_width 0.5)
				(island_removal_mode 0)
			)
			(polygon
				(pts
					(xy 169.997628 -133.592316) (xy 184.3024 -133.592316) (xy 184.3024 -134.100316) (xy 169.997628 -134.100316)
				)
			)
		)
		(zone
			(layer "F.Cu")
			(hatch none 0.5)
			(connect_pads
				(clearance 0)
			)
			(min_thickness 0.25)
			(keepout
				(tracks allowed)
				(vias not_allowed)
				(pads allowed)
				(copperpour not_allowed)
				(footprints allowed)
			)
			(placement
				(enabled no)
				(sheetname "")
			)
			(fill
				(thermal_gap 0.5)
				(thermal_bridge_width 0.5)
				(island_removal_mode 0)
			)
			(polygon
				(pts
					(xy 170.247564 -128.099566) (xy 184.552336 -128.099566) (xy 184.552336 -128.607566) (xy 170.247564 -128.607566)
				)
			)
		)
		(zone
			(layer "F.Cu")
			(hatch none 0.5)
			(connect_pads
				(clearance 0)
			)
			(min_thickness 0.25)
			(keepout
				(tracks allowed)
				(vias not_allowed)
				(pads allowed)
				(copperpour not_allowed)
				(footprints allowed)
			)
			(placement
				(enabled no)
				(sheetname "")
			)
			(fill
				(thermal_gap 0.5)
				(thermal_bridge_width 0.5)
				(island_removal_mode 0)
			)
			(polygon
				(pts
					(xy 186.497468 -133.592316) (xy 188.802264 -133.592316) (xy 188.802264 -134.100316) (xy 186.497468 -134.100316)
				)
			)
		)
		(zone
			(layer "F.Cu")
			(hatch none 0.5)
			(connect_pads
				(clearance 0)
			)
			(min_thickness 0.25)
			(keepout
				(tracks allowed)
				(vias not_allowed)
				(pads allowed)
				(copperpour not_allowed)
				(footprints allowed)
			)
			(placement
				(enabled no)
				(sheetname "")
			)
			(fill
				(thermal_gap 0.5)
				(thermal_bridge_width 0.5)
				(island_removal_mode 0)
			)
			(polygon
				(pts
					(xy 186.747658 -128.099566) (xy 188.552328 -128.099566) (xy 188.552328 -128.607566) (xy 186.747658 -128.607566)
				)
			)
		)
		(zone
			(layers "F.Cu" "B.Cu" "In1.Cu" "In2.Cu" "In3.Cu" "In4.Cu" "In5.Cu" "In6.Cu")
			(hatch none 0.5)
			(connect_pads
				(clearance 0)
			)
			(min_thickness 0.25)
			(keepout
				(tracks not_allowed)
				(vias allowed)
				(pads allowed)
				(copperpour not_allowed)
				(footprints allowed)
			)
			(placement
				(enabled no)
				(sheetname "")
			)
			(fill
				(thermal_gap 0.5)
				(thermal_bridge_width 0.5)
				(island_removal_mode 0)
			)
			(polygon
				(pts
					(arc
						(start 170.263566 -129.599944)
						(mid 168.536366 -129.599944)
						(end 170.263566 -129.599944)
					)
				)
			)
		)
		(zone
			(layers "F.Cu" "B.Cu" "In1.Cu" "In2.Cu" "In3.Cu" "In4.Cu" "In5.Cu" "In6.Cu")
			(hatch none 0.5)
			(connect_pads
				(clearance 0)
			)
			(min_thickness 0.25)
			(keepout
				(tracks not_allowed)
				(vias allowed)
				(pads allowed)
				(copperpour not_allowed)
				(footprints allowed)
			)
			(placement
				(enabled no)
				(sheetname "")
			)
			(fill
				(thermal_gap 0.5)
				(thermal_bridge_width 0.5)
				(island_removal_mode 0)
			)
			(polygon
				(pts
					(arc
						(start 190.504826 -129.599944)
						(mid 188.295026 -129.599944)
						(end 190.504826 -129.599944)
					)
				)
			)
		)
	)
	(footprint ""
		(layer "F.Cu")
		(at 102.999794 -9.99998)
		(property "Reference" ""
			(at 0 0 0)
			(layer "F.SilkS")
			(hide yes)
			(effects
				(font
					(size 1.27 1.27)
				)
			)
		)
		(property "Value" "*"
			(at -6.38175 0.19685 0)
			(unlocked yes)
			(layer "F.Fab")
			(hide yes)
			(effects
				(font
					(size 1.016 1.016)
					(thickness 0.1524)
				)
			)
		)
		(duplicate_pad_numbers_are_jumpers no)
		(fp_poly
			(pts
				(arc
					(start 5.0673 0)
					(mid -5.0673 0)
					(end 5.0673 0)
				)
			)
			(stroke
				(width 0)
				(type default)
			)
			(fill no)
			(layer "B.CrtYd")
		)
		(fp_poly
			(pts
				(arc
					(start 5.0673 0)
					(mid -5.0673 0)
					(end 5.0673 0)
				)
			)
			(stroke
				(width 0)
				(type default)
			)
			(fill no)
			(layer "F.CrtYd")
		)
		(fp_poly
			(pts
				(arc
					(start 5.0673 0)
					(mid -5.0673 0)
					(end 5.0673 0)
				)
			)
			(stroke
				(width 0)
				(type default)
			)
			(fill no)
			(layer "B.Fab")
		)
		(fp_poly
			(pts
				(arc
					(start 5.0673 0)
					(mid -5.0673 0)
					(end 5.0673 0)
				)
			)
			(stroke
				(width 0)
				(type default)
			)
			(fill no)
			(layer "F.Fab")
		)
		(pad "1" thru_hole circle
			(at 0 0)
			(size 9.525 9.525)
			(drill 3.5052)
			(layers "*.Cu" "*.Mask")
			(remove_unused_layers no)
			(net "Net_35")
			(clearance -2.5019)
			(thermal_gap 0.3048)
			(padstack
				(mode front_inner_back)
				(layer "Inner"
					(shape circle)
					(size 3.9116 3.9116)
					(clearance 0.3048)
				)
				(layer "B.Cu"
					(shape circle)
					(size 9.525 9.525)
					(clearance -2.5019)
				)
			)
		)
	)
)
